FILE_TYPE = CONNECTIVITY;
{Allegro Design Entry HDL 17.2-2016 S081 (4005846) 1/11/2022}
"PAGE_NUMBER" = 201;
0"NC";
1"P3V3_AUX\g";
2"VFG3P3_CLK_GEN\g";
3"P3V3_AUX\g";
4"P3V3_AUX\g";
5"P3V3_AUX\g";
6"VFG_3P3A_CLK_GEN\g";
7"P3V3_AUX\g";
8"P3V3_AUX\g";
9"VFG_3P3A_CLK_GEN\g";
10"VFG3P3_CLK_GEN\g";
11"P3V3_AUX\g";
12"GND\g";
13"GND\g";
14"GND\g";
15"GND\g";
16"GND\g";
17"GND\g";
18"GND\g";
19"GND\g";
20"GND\g";
21"GND\g";
22"GND\g";
23"GND\g";
24"P3V3_PWRGD_CLKGEN"CDS_PHYS_NET_NAME"FM_PCH_PRSNT_N";
25"CLK_GEN2_XTAL_IN";
26"CLK_GEN2_XTAL_OUT";
27"CLK_GEN2_SMB_SADR"CDS_PHYS_NET_NAME"FM_PCH_PRSNT_N";
28"SMB_HOST_CLK_GEN2_3V3AUX_SCL";
29"SMB_HOST_CLK_GEN2_3V3AUX_SDA";
30"CLK_GEN2_BMC_RC_OE_R3_N";
31"CLK_100M_BMC_RC_DP_R";
32"CLK_100M_BMC_RC_DN_R";
33"CLK_100M_GPU_FPGA_DP_R";
34"CLK_100M_GPU_FPGA_DN_R";
35"CLK_GEN2_GPU_OE_N";
36"FG_SS_EN"CDS_PHYS_NET_NAME"FM_PCH_PRSNT_N";
37"CLK_GEN2_XTAL_IN_R";
38"CLK_GEN2_BMC_RC_OE_N";
39"CLK_GEN2_GPU_FPGA_OE_OR_N";
40"GPU_FPGA_READY_R_N";
41"CLK_GEN2_GPU_FPGA_OE_R2_N";
42"CLK_GEN2_SMB_SADR"CDS_PHYS_NET_NAME"FM_PCH_PRSNT_N";
43"CLK_GEN2_GPU_FPGA_OE_N";
44"GPU_FPGA_READY_N";
45"CLK_100M_GPU_FPGA_DN";
46"CLK_100M_GPU_FPGA_DP";
47"CLK_GEN2_GPU_FPGA_OE_OR_N";
48"FG_SS_EN"CDS_PHYS_NET_NAME"FM_PCH_PRSNT_N";
49"CLK_100M_BMC_RC_DP";
50"CLK_100M_BMC_RC_DN";
51"P3V3_PWRGD_CLKGEN"CDS_PHYS_NET_NAME"FM_PCH_PRSNT_N";
%"Q_RES"
"1","(-1275,5200)","0","pure_quanta","I102";
;
PART_NUMBER"CS-1002FB04"
MATERIAL"CHIP"
TOLERANCE"1%"
VALUE"1"
WATTAGE"1/16W"
PACK_TYPE"0402LF"
$LOCATION"R4077"
CDS_LIB"pure_quanta"
CDS_LOCATION"R4077"
$SEC"1"
CDS_SEC"1";
"B"
$PN"2"9;
"A"
$PN"1"10;
%"Q_CAP"
"1","(-1050,4975)","0","pure_quanta","I103";
;
PART_NUMBER"CH5104KEB02"
VALUE"1UF"
VOLTAGE"25V"
MATERIAL"X6S"
PACK_TYPE"C0402"
TOLERANCE"10%"
$LOCATION"C1884"
CDS_LIB"pure_quanta"
BOM_COST"VR_SYSTEM "
CDS_LOCATION"C1884"
$SEC"1"
CDS_SEC"1";
"B"
$PN"2"17;
"A"
$PN"1"9;
%"Q_CAP"
"1","(-2400,5000)","0","pure_quanta","I104";
;
PART_NUMBER"CH4104K1B00"
PACK_TYPE"0402"
TOLERANCE"10%"
VOLTAGE"25V"
MATERIAL"X7R"
VALUE"0.1UF"
$LOCATION"C2257"
CDS_LIB"pure_quanta"
CDS_LOCATION"C2257"
$SEC"1"
CDS_SEC"1";
"B"
$PN"2"16;
"A"
$PN"1"10;
%"Q_CAP"
"1","(-1600,5000)","0","pure_quanta","I105";
;
PART_NUMBER"CH4104K1B00"
VALUE"0.1UF"
VOLTAGE"25V"
TOLERANCE"10%"
MATERIAL"X7R"
PACK_TYPE"0402"
$LOCATION"C2258"
CDS_LIB"pure_quanta"
CDS_LOCATION"C2258"
$SEC"1"
CDS_SEC"1";
"B"
$PN"2"16;
"A"
$PN"1"10;
%"Q_CAP"
"1","(-725,4975)","0","pure_quanta","I106";
;
PART_NUMBER"CH4104K1B00"
MATERIAL"X7R"
PACK_TYPE"0402"
VALUE"0.1UF"
VOLTAGE"25V"
TOLERANCE"10%"
$LOCATION"C2259"
CDS_LIB"pure_quanta"
CDS_LOCATION"C2259"
$SEC"1"
CDS_SEC"1";
"B"
$PN"2"17;
"A"
$PN"1"9;
%"UNIVERSAL_GND"
"1","(-725,4650)","0","logical_power","I107";
;
HDL_POWER"GND"
CDS_LIB"logical_power";
"A"17;
%"UNIVERSAL_POWER"
"1","(-2400,5350)","0","logical_power","I108";
;
HDL_POWER"VFG3P3_CLK_GEN"
CDS_LIB"logical_power";
"A"10;
%"UNIVERSAL_POWER"
"1","(-725,5300)","0","logical_power","I109";
;
HDL_POWER"VFG_3P3A_CLK_GEN"
CDS_LIB"logical_power";
"A"9;
%"UNIVERSAL_POWER"
"1","(-2850,4300)","0","logical_power","I110";
;
HDL_POWER"VFG3P3_CLK_GEN"
CDS_LIB"logical_power";
"A"2;
%"UNIVERSAL_POWER"
"1","(-2500,4375)","0","logical_power","I111";
;
HDL_POWER"VFG_3P3A_CLK_GEN"
CDS_LIB"logical_power";
"A"6;
%"UNIVERSAL_GND"
"1","(-4350,3500)","0","logical_power","I113";
;
HDL_POWER"GND"
CDS_LIB"logical_power";
"A"12;
%"UNIVERSAL_GND"
"1","(-4225,3600)","0","logical_power","I115";
;
CDS_LIB"logical_power"
HDL_POWER"GND";
"A"13;
%"UNIVERSAL_GND"
"1","(-3575,3600)","0","logical_power","I116";
;
HDL_POWER"GND"
CDS_LIB"logical_power";
"A"15;
%"UNIVERSAL_GND"
"1","(-3475,3475)","0","logical_power","I117";
;
HDL_POWER"GND"
CDS_LIB"logical_power";
"A"14;
%"Q_RES"
"2","(250,1475)","2","pure_quanta","I127";
;
PART_NUMBER"CS31002FB08"
MATERIAL"EMPTY"
TOLERANCE"1%"
VALUE"10K"
WATTAGE"1/16W"
PACK_TYPE"0402LF"
$LOCATION"R4078"
CDS_LIB"pure_quanta"
CDS_LOCATION"R4078"
$SEC"1"
CDS_SEC"1";
"A"
$PN"1"11;
"B"
$PN"2"48;
%"Q_RES"
"2","(250,1000)","2","pure_quanta","I128";
;
PART_NUMBER"CS31002FB08"
TOLERANCE"1%"
VALUE"10K"
PACK_TYPE"0402LF"
WATTAGE"1/16W"
MATERIAL"CHIP"
$LOCATION"R4079"
CDS_LIB"pure_quanta"
CDS_LOCATION"R4079"
$SEC"1"
CDS_SEC"1";
"A"
$PN"1"48;
"B"
$PN"2"18;
%"UNIVERSAL_POWER"
"1","(1575,1775)","0","logical_power","I130";
;
HDL_POWER"P3V3_AUX"
CDS_LIB"logical_power";
"A"8;
%"UNIVERSAL_GND"
"1","(1575,750)","0","logical_power","I133";
;
HDL_POWER"GND"
CDS_LIB"logical_power";
"A"19;
%"Q_RES"
"2","(1575,1025)","2","pure_quanta","I134";
;
PART_NUMBER"CS31002FB08"
MATERIAL"EMPTY"
VALUE"10K"
WATTAGE"1/16W"
TOLERANCE"1%"
PACK_TYPE"0402LF"
$LOCATION"R4082"
CDS_LIB"pure_quanta"
CDS_LOCATION"R4082"
$SEC"1"
CDS_SEC"1";
"A"
$PN"1"42;
"B"
$PN"2"19;
%"Q_RES"
"2","(1575,1500)","2","pure_quanta","I135";
;
PART_NUMBER"CS31002FB08"
TOLERANCE"1%"
VALUE"10K"
WATTAGE"1/16W"
PACK_TYPE"0402LF"
MATERIAL"CHIP"
$LOCATION"R4081"
CDS_LIB"pure_quanta"
CDS_LOCATION"R4081"
$SEC"1"
CDS_SEC"1";
"A"
$PN"1"8;
"B"
$PN"2"42;
%"UNIVERSAL_POWER"
"1","(1575,2575)","0","logical_power","I141";
;
HDL_POWER"P3V3_AUX"
CDS_LIB"logical_power";
"A"5;
%"Q_RES"
"2","(1575,2300)","2","pure_quanta","I142";
;
PART_NUMBER"CS31002FB08"
VALUE"10K"
TOLERANCE"1%"
WATTAGE"1/16W"
MATERIAL"CHIP"
PACK_TYPE"0402LF"
$LOCATION"R4080"
CDS_LIB"pure_quanta"
CDS_LOCATION"R4080"
$SEC"1"
CDS_SEC"1";
"A"
$PN"1"5;
"B"
$PN"2"51;
%"Q_RES"
"1","(-3300,3300)","0","pure_quanta","I146";
;
PART_NUMBER"CS00002JB13"
TOLERANCE"5%"
VALUE"0"
WATTAGE"1/16W"
PACK_TYPE"0402LF"
MATERIAL"CHIP"
$LOCATION"R4076"
CDS_LIB"pure_quanta"
CDS_LOCATION"R4076"
$SEC"1"
CDS_SEC"1";
"B"
$PN"2"35;
"A"
$PN"1"39;
%"Q_RES"
"1","(-3300,3350)","0","pure_quanta","I147";
;
PART_NUMBER"CS00002JB13"
VALUE"0"
MATERIAL"CHIP"
$LOCATION"R4075"
WATTAGE"1/16W"
TOLERANCE"5%"
PACK_TYPE"0402LF"
CDS_LIB"pure_quanta"
CDS_LOCATION"R4075"
$SEC"1"
CDS_SEC"1";
"B"
$PN"2"30;
"A"
$PN"1"38;
%"Q_INDUCTOR"
"1","(-3150,5225)","0","pure_quanta","I155";
;
PART_NUMBER"CX601T05003"
PACK_TYPE"SMLF"
MATERIAL"IND"
VALUE"FCM2012KF-601T/0.5A"
LOCATION"L17"
CDS_LIB"pure_quanta"
NEEDS_NO_SIZE"TRUE"
$SEC"1"
CDS_SEC"1";
"1"
$PN"1"3;
"2"
$PN"2"10;
%"UNIVERSAL_POWER"
"1","(-3425,1875)","0","logical_power","I156";
;
HDL_POWER"P3V3_AUX"
CDS_LIB"logical_power";
"A"7;
%"Q_RES"
"2","(-3425,1600)","0","pure_quanta","I157";
;
PART_NUMBER"CS24702FB06"
TOLERANCE"1%"
VALUE"4.7K"
PACK_TYPE"0402LF"
WATTAGE"1/16W"
MATERIAL"CHIP"
$LOCATION"R3322"
CDS_LIB"pure_quanta"
CDS_LOCATION"R3322"
$SEC"1"
CDS_SEC"1";
"A"
$PN"1"7;
"B"
$PN"2"41;
%"74LVC1G32GW"
"1","(-2225,1250)","0","pure_quanta","I158";
;
PART_NUMBER"ALVC1G32007"
MATERIAL"IC"
VALUE"74LVC1G32GW"
PACK_TYPE"SMLF"
LOCATION"U248"
NEEDS_NO_SIZE"TRUE"
CDS_LIB"pure_quanta"
$SEC"1"
CDS_SEC"1";
"GND"
$PN"3"22;
"O"
$PN"4"47;
"I1"
$PN"2"41;
"VCC"
$PN"5"4;
"I0"
$PN"1"40;
%"Q_XTAL_4P_13BI_24GND"
"1","(-3900,3825)","0","pure_quanta","I159";
;
PART_NUMBER"BG6250000F0"
PART_TYPE"SMLF"
VALUE"25MHZ"
MATERIAL"MISC"
LOCATION"Y3"
PIN_NAMES_ROTATE"True"
CDS_LMAN_SYM_OUTLINE"-125,175,125,-175"
CDS_LIB"pure_quanta"
$SEC"1"
CDS_SEC"1";
"X2"
$PN"3"26;
"G2"
$PN"4"15;
"G1"
$PN"2"13;
"X1"
$PN"1"37;
%"Q_CAP"
"1","(-2800,5000)","0","pure_quanta","I16";
;
PART_NUMBER"CH6104KEA00"
VALUE"10UF"
MATERIAL"X6S"
TOLERANCE"10%"
VOLTAGE"25V"
PACK_TYPE"C0805"
$LOCATION"C1883"
CDS_LIB"pure_quanta"
CDS_LOCATION"C1883"
$SEC"1"
CDS_SEC"1";
"B"
$PN"2"16;
"A"
$PN"1"10;
%"Q_RES"
"1","(-3475,4375)","0","pure_quanta","I160";
;
PART_NUMBER"CS00002JB13"
MATERIAL"CHIP"
WATTAGE"1/16W"
VALUE"0"
TOLERANCE"5%"
PACK_TYPE"0402LF"
$LOCATION"R4501"
CDS_LIB"pure_quanta"
CDS_LOCATION"R4501"
$SEC"1"
CDS_SEC"1";
"B"
$PN"2"25;
"A"
$PN"1"37;
%"Q_RES"
"2","(-3400,975)","0","pure_quanta","I161";
;
PART_NUMBER"CS24702FB06"
WATTAGE"1/16W"
MATERIAL"EMPTY"
PACK_TYPE"0402LF"
VALUE"4.7K"
TOLERANCE"1%"
$LOCATION"R4514"
CDS_LIB"pure_quanta"
CDS_LOCATION"R4514"
$SEC"1"
CDS_SEC"1";
"A"
$PN"1"41;
"B"
$PN"2"23;
%"UNIVERSAL_GND"
"1","(-3400,525)","0","logical_power","I162";
;
CDS_LIB"logical_power"
HDL_POWER"GND";
"A"23;
%"Q_RES"
"2","(-5075,3725)","0","pure_quanta","I163";
;
PART_NUMBER"CS31002FB08"
TOLERANCE"1%"
VALUE"10K"
MATERIAL"CHIP"
WATTAGE"1/16W"
PACK_TYPE"0402LF"
$LOCATION"R4521"
CDS_LIB"pure_quanta"
CDS_LOCATION"R4521"
$SEC"1"
CDS_SEC"1";
"A"
$PN"1"1;
"B"
$PN"2"38;
%"UNIVERSAL_POWER"
"1","(-5075,4000)","0","logical_power","I164";
;
HDL_POWER"P3V3_AUX"
CDS_LIB"logical_power";
"A"1;
%"Q_CAP"
"1","(-4350,3700)","0","pure_quanta","I165";
;
PART_NUMBER"CH-8216TB09"
MATERIAL"NP0"
TOLERANCE"0.1P"
VOLTAGE"50V"
VALUE"8.2PF"
PACK_TYPE"C0402"
LOCATION"C2255"
CDS_LIB"pure_quanta"
$SEC"1"
CDS_SEC"1";
"B"
$PN"2"12;
"A"
$PN"1"37;
%"Q_CAP"
"1","(-3475,3700)","0","pure_quanta","I166";
;
PART_NUMBER"CH-8216TB09"
VALUE"8.2PF"
VOLTAGE"50V"
TOLERANCE"0.1P"
PACK_TYPE"C0402"
MATERIAL"NP0"
LOCATION"C2256"
CDS_LIB"pure_quanta"
$SEC"1"
CDS_SEC"1";
"B"
$PN"2"14;
"A"
$PN"1"26;
%"9FGL0251DKILFT"
"1","(-1400,3500)","0","pure_quanta","I167";
;
PART_NUMBER"AL000251002"
VALUE"9FGL0251DKILFT"
MATERIAL"IC"
PART_TYPE"SMLF"
LOCATION"U247"
NEEDS_NO_SIZE"TRUE"
CDS_LMAN_SYM_OUTLINE"-400,700,400,-700"
CDS_LIB"pure_quanta"
$SEC"1"
CDS_SEC"1";
"TH_GND"
$PN"25"20;
"GNDXTAL"
$PN"24"20;
"^VSS_EN_TRI"
$PN"23"36;
"^CKPWRGD_PD# \B"
$PN"22"24;
"GND_21"
$PN"21"20;
"VDD3.3_20"
$PN"20"2;
"VOE1# \B"
$PN"19"35;
"DIF1# \B"
$PN"18"34;
"DIF1"
$PN"17"33;
"VDDA3.3"
$PN"16"6;
"GNDA"
$PN"15"20;
"DIF0# \B"
$PN"14"32;
"DIF0"
$PN"13"31;
"VOE0# \B"
$PN"12"30;
"VDD3.3_11"
$PN"11"2;
"GND_10"
$PN"10"20;
"SDATA_3.3"
$PN"9"29;
"SCLK_3.3"
$PN"8"28;
"VDDDIG3.3"
$PN"7"2;
"GNDDIG"
$PN"6"20;
"GNDREF"
$PN"5"20;
"VSADR||REF3.3"
$PN"4"27;
"VDDXTAL3.3"
$PN"3"2;
"X2"
$PN"2"26;
"XIN||CLKIN_25"
$PN"1"25;
%"Q_CAP"
"1","(-2075,5000)","0","pure_quanta","I18";
;
PART_NUMBER"CH4104K1B00"
VALUE"0.1UF"
VOLTAGE"25V"
TOLERANCE"10%"
PACK_TYPE"0402"
MATERIAL"X7R"
$LOCATION"C1886"
CDS_LIB"pure_quanta"
CDS_LOCATION"C1886"
$SEC"1"
CDS_SEC"1";
"B"
$PN"2"16;
"A"
$PN"1"10;
%"Q_CAP"
"1","(-1850,5000)","0","pure_quanta","I19";
;
PART_NUMBER"CH4104K1B00"
VALUE"0.1UF"
VOLTAGE"25V"
TOLERANCE"10%"
MATERIAL"X7R"
PACK_TYPE"0402"
$LOCATION"C1889"
CDS_LIB"pure_quanta"
CDS_LOCATION"C1889"
$SEC"1"
CDS_SEC"1";
"B"
$PN"2"16;
"A"
$PN"1"10;
%"UNIVERSAL_POWER"
"1","(-3500,5325)","0","logical_power","I20";
;
HDL_POWER"P3V3_AUX"
CDS_LIB"logical_power";
"A"3;
%"UNIVERSAL_GND"
"1","(-1600,4650)","0","logical_power","I21";
;
CDS_LIB"logical_power"
HDL_POWER"GND";
"A"16;
%"UNIVERSAL_GND"
"1","(-700,2500)","0","logical_power","I22";
;
HDL_POWER"GND"
CDS_LIB"logical_power";
"A"20;
%"UNIVERSAL_POWER"
"1","(250,1750)","0","logical_power","I33";
;
HDL_POWER"P3V3_AUX"
CDS_LIB"logical_power";
"A"11;
%"UNIVERSAL_GND"
"1","(250,725)","0","logical_power","I35";
;
HDL_POWER"GND"
CDS_LIB"logical_power";
"A"18;
%"Q_RES"
"1","(175,3750)","0","pure_quanta","I69";
;
PART_NUMBER"CS00002JB13"
VALUE"0"
MATERIAL"CHIP"
$LOCATION"R3335"
PACK_TYPE"0402LF"
TOLERANCE"5%"
WATTAGE"1/16W"
CDS_LIB"pure_quanta"
CDS_LOCATION"R3335"
$SEC"1"
CDS_SEC"1";
"B"
$PN"2"49;
"A"
$PN"1"31;
%"Q_RES"
"1","(175,3700)","0","pure_quanta","I74";
;
PART_NUMBER"CS00002JB13"
VALUE"0"
MATERIAL"CHIP"
$LOCATION"R3336"
CDS_LIB"pure_quanta"
PACK_TYPE"0402LF"
TOLERANCE"5%"
WATTAGE"1/16W"
CDS_LOCATION"R3336"
$SEC"1"
CDS_SEC"1";
"B"
$PN"2"50;
"A"
$PN"1"32;
%"Q_RES"
"1","(175,3600)","0","pure_quanta","I75";
;
PART_NUMBER"CS00002JB13"
MATERIAL"CHIP"
VALUE"0"
$LOCATION"R3337"
CDS_LIB"pure_quanta"
WATTAGE"1/16W"
TOLERANCE"5%"
PACK_TYPE"0402LF"
CDS_LOCATION"R3337"
$SEC"1"
CDS_SEC"1";
"B"
$PN"2"46;
"A"
$PN"1"33;
%"Q_RES"
"1","(175,3550)","0","pure_quanta","I76";
;
PART_NUMBER"CS00002JB13"
VALUE"0"
TOLERANCE"5%"
MATERIAL"CHIP"
PACK_TYPE"0402LF"
WATTAGE"1/16W"
$LOCATION"R3338"
CDS_LIB"pure_quanta"
CDS_LOCATION"R3338"
$SEC"1"
CDS_SEC"1";
"B"
$PN"2"45;
"A"
$PN"1"34;
%"UNIVERSAL_POWER"
"1","(-2375,2350)","0","logical_power","I79";
;
HDL_POWER"P3V3_AUX"
CDS_LIB"logical_power";
"A"4;
%"Q_CAP"
"1","(-2375,1925)","0","pure_quanta","I80";
;
PART_NUMBER"CH4104K1B00"
VOLTAGE"25V"
VALUE"0.1UF"
MATERIAL"X7R"
TOLERANCE"10%"
PACK_TYPE"0402"
$LOCATION"C1882"
CDS_LIB"pure_quanta"
CDS_LOCATION"C1882"
$SEC"1"
CDS_SEC"1";
"B"
$PN"2"21;
"A"
$PN"1"4;
%"UNIVERSAL_GND"
"1","(-2375,1675)","0","logical_power","I81";
;
CDS_LIB"logical_power"
HDL_POWER"GND";
"A"21;
%"UNIVERSAL_GND"
"1","(-2550,975)","0","logical_power","I82";
;
HDL_POWER"GND"
CDS_LIB"logical_power";
"A"22;
%"Q_RES"
"1","(-3725,1300)","0","pure_quanta","I84";
;
PART_NUMBER"CS00002JB13"
MATERIAL"CHIP"
VALUE"0"
$LOCATION"R3326"
WATTAGE"1/16W"
TOLERANCE"5%"
PACK_TYPE"0402LF"
CDS_LIB"pure_quanta"
CDS_LOCATION"R3326"
$SEC"1"
CDS_SEC"1";
"B"
$PN"2"40;
"A"
$PN"1"44;
%"Q_RES"
"1","(-3725,1200)","0","pure_quanta","I85";
;
PART_NUMBER"CS00002JB13"
WATTAGE"1/16W"
TOLERANCE"5%"
MATERIAL"CHIP"
PACK_TYPE"0402LF"
VALUE"0"
$LOCATION"R3327"
CDS_LIB"pure_quanta"
CDS_LOCATION"R3327"
$SEC"1"
CDS_SEC"1";
"B"
$PN"2"41;
"A"
$PN"1"43;
END.
